# T6G (Grand Teton) — schematic netlist excerpt (pin names and nets, part order shuffled) for the footprints in the layout excerpt that follows; sources: Cadence DE-HDL packaged netlist, KiCad conversion of 04192023_DAF0TMB3IC0_F0TG_MB_C_brd_V02_OCP.brd

PR6538  Q_RES  1 1% CHIP  pkg 0402LF  page 364 : A = P0V9_RETIMER_CPU1_VCC ; B = P3V3_AUX
R1465  Q_RES  4.7K 5% EMPTY  pkg 0201LF  page 320 : A = P1V8_CPU1_RT_1D ; B = JTAG_TMS_RT_CPU1_P0
R6851  Q_RES  33 5% CHIP  pkg 0402LF  page 80 : A = P1V8_RETIMER_CPU1_EN ; B = P1V8_RETIMER_CPU1_R_EN

(kicad_pcb
	(version 20260206)
	(generator "pcbnew")
	(generator_version "10.0")
	(general
		(thickness 1.6)
		(legacy_teardrops no)
	)
	(paper "A4")
	(title_block
		(title "04192023_DAF0TMB3IC0_F0TG_MB_C_brd_V02_OCP.brd")
		(comment 1 "Grand Teton / footprints 327-329 of 8354")
	)
	(layers
		(0 "F.Cu" signal "TOP")
		(4 "In1.Cu" signal "GND")
		(6 "In2.Cu" signal "IN1")
		(8 "In3.Cu" signal "GND1")
		(10 "In4.Cu" signal "IN2")
		(12 "In5.Cu" signal "GND2")
		(14 "In6.Cu" signal "IN3")
		(16 "In7.Cu" signal "GND3")
		(18 "In8.Cu" signal "VCC")
		(20 "In9.Cu" signal "VCC1")
		(22 "In10.Cu" signal "GND4")
		(24 "In11.Cu" signal "IN4")
		(26 "In12.Cu" signal "GND5")
		(28 "In13.Cu" signal "IN5")
		(30 "In14.Cu" signal "GND6")
		(32 "In15.Cu" signal "IN6")
		(34 "In16.Cu" signal "GND7")
		(2 "B.Cu" signal "BOTTOM")
		(9 "F.Adhes" user "F.Adhesive")
		(11 "B.Adhes" user "B.Adhesive")
		(13 "F.Paste" user "Package Geometry/Pastemask Top")
		(15 "B.Paste" user "Package Geometry/Pastemask Bottom")
		(5 "F.SilkS" user "Ref Des/Silkscreen Top")
		(7 "B.SilkS" user "Ref Des/Silkscreen Bottom")
		(1 "F.Mask" user "Board Geometry/Soldermask Top")
		(3 "B.Mask" user "Board Geometry/Soldermask Bottom")
		(17 "Dwgs.User" user "User.Drawings")
		(19 "Cmts.User" user "User.Comments")
		(21 "Eco1.User" user "User.Eco1")
		(23 "Eco2.User" user "User.Eco2")
		(25 "Edge.Cuts" user "Board Geometry/Outline")
		(27 "Margin" user)
		(31 "F.CrtYd" user "Package Geometry/Place Bound Top")
		(29 "B.CrtYd" user "Package Geometry/Place Bound Bottom")
		(35 "F.Fab" user "Ref Des/Assembly Top")
		(33 "B.Fab" user "Ref Des/Assembly Bottom")
	)
	(footprint ""
		(layer "F.Cu")
		(at 45.932344 -418.888164)
		(property "Reference" "R1465"
			(at 0 0 0)
			(layer "F.SilkS")
			(hide yes)
			(effects
				(font
					(size 1.27 1.27)
				)
			)
		)
		(property "Value" ""
			(at 0 0 0)
			(layer "F.Fab")
			(effects
				(font
					(size 1.27 1.27)
				)
			)
		)
		(duplicate_pad_numbers_are_jumpers no)
		(fp_line
			(start -0.32512 -0.175006)
			(end 0.32512 -0.175006)
			(stroke
				(width 0.1)
				(type default)
			)
			(layer "F.Fab")
		)
		(fp_line
			(start -0.32512 0.175006)
			(end -0.32512 -0.175006)
			(stroke
				(width 0.1)
				(type default)
			)
			(layer "F.Fab")
		)
		(fp_line
			(start 0.32512 -0.175006)
			(end 0.32512 0.175006)
			(stroke
				(width 0.1)
				(type default)
			)
			(layer "F.Fab")
		)
		(fp_line
			(start 0.32512 0.175006)
			(end -0.32512 0.175006)
			(stroke
				(width 0.1)
				(type default)
			)
			(layer "F.Fab")
		)
		(pad "1" smd rect
			(at -0.2667 0)
			(size 0.3048 0.381)
			(layers "F.Cu" "F.Mask" "F.Paste")
			(net "P1V8_CPU1_RT_1D")
		)
		(pad "2" smd rect
			(at 0.2667 0 180)
			(size 0.3048 0.381)
			(layers "F.Cu" "F.Mask" "F.Paste")
			(net "JTAG_TMS_RT_CPU1_P0")
		)
	)
	(footprint ""
		(layer "F.Cu")
		(at 169.744644 -128.24333)
		(property "Reference" "R6851"
			(at 0 0 0)
			(layer "F.SilkS")
			(hide yes)
			(effects
				(font
					(size 1.27 1.27)
				)
			)
		)
		(property "Value" ""
			(at 0 0 0)
			(layer "F.Fab")
			(effects
				(font
					(size 1.27 1.27)
				)
			)
		)
		(duplicate_pad_numbers_are_jumpers no)
		(fp_line
			(start -0.7874 -0.4064)
			(end 0.7874 -0.4064)
			(stroke
				(width 0.1524)
				(type default)
			)
			(layer "F.SilkS")
		)
		(fp_line
			(start -0.7874 0.4064)
			(end -0.7874 -0.4064)
			(stroke
				(width 0.1524)
				(type default)
			)
			(layer "F.SilkS")
		)
		(fp_line
			(start 0.7874 -0.4064)
			(end 0.7874 0.4064)
			(stroke
				(width 0.1524)
				(type default)
			)
			(layer "F.SilkS")
		)
		(fp_line
			(start 0.7874 0.4064)
			(end -0.7874 0.4064)
			(stroke
				(width 0.1524)
				(type default)
			)
			(layer "F.SilkS")
		)
		(fp_line
			(start -0.67945 -0.305054)
			(end -0.12065 -0.305054)
			(stroke
				(width 0.1)
				(type default)
			)
			(layer "F.Fab")
		)
		(fp_line
			(start -0.67945 0.3048)
			(end -0.67945 -0.305054)
			(stroke
				(width 0.1)
				(type default)
			)
			(layer "F.Fab")
		)
		(fp_line
			(start -0.12065 -0.305054)
			(end -0.12065 -0.2794)
			(stroke
				(width 0.1)
				(type default)
			)
			(layer "F.Fab")
		)
		(fp_line
			(start -0.12065 -0.2794)
			(end 0.12065 -0.2794)
			(stroke
				(width 0.1)
				(type default)
			)
			(layer "F.Fab")
		)
		(fp_line
			(start -0.12065 0.2794)
			(end -0.12065 0.3048)
			(stroke
				(width 0.1)
				(type default)
			)
			(layer "F.Fab")
		)
		(fp_line
			(start -0.12065 0.3048)
			(end -0.67945 0.3048)
			(stroke
				(width 0.1)
				(type default)
			)
			(layer "F.Fab")
		)
		(fp_line
			(start 0.120396 0.2794)
			(end -0.12065 0.2794)
			(stroke
				(width 0.1)
				(type default)
			)
			(layer "F.Fab")
		)
		(fp_line
			(start 0.120396 0.3048)
			(end 0.120396 0.2794)
			(stroke
				(width 0.1)
				(type default)
			)
			(layer "F.Fab")
		)
		(fp_line
			(start 0.12065 -0.3048)
			(end 0.67945 -0.3048)
			(stroke
				(width 0.1)
				(type default)
			)
			(layer "F.Fab")
		)
		(fp_line
			(start 0.12065 -0.2794)
			(end 0.12065 -0.3048)
			(stroke
				(width 0.1)
				(type default)
			)
			(layer "F.Fab")
		)
		(fp_line
			(start 0.67945 -0.3048)
			(end 0.67945 0.3048)
			(stroke
				(width 0.1)
				(type default)
			)
			(layer "F.Fab")
		)
		(fp_line
			(start 0.67945 0.3048)
			(end 0.120396 0.3048)
			(stroke
				(width 0.1)
				(type default)
			)
			(layer "F.Fab")
		)
		(pad "1" smd circle
			(at -0.40005 0)
			(size 0 0)
			(layers "F.Cu" "F.Mask" "F.Paste")
			(net "P1V8_RETIMER_CPU1_EN")
		)
		(pad "2" smd circle
			(at 0.40005 0)
			(size 0 0)
			(layers "F.Cu" "F.Mask" "F.Paste")
			(net "P1V8_RETIMER_CPU1_R_EN")
		)
	)
	(footprint ""
		(layer "F.Cu")
		(at 10.066782 -404.976584 180)
		(property "Reference" "PR6538"
			(at 0 0 180)
			(layer "F.SilkS")
			(hide yes)
			(effects
				(font
					(size 1.27 1.27)
				)
			)
		)
		(property "Value" ""
			(at 0 0 180)
			(layer "F.Fab")
			(effects
				(font
					(size 1.27 1.27)
				)
			)
		)
		(duplicate_pad_numbers_are_jumpers no)
		(fp_line
			(start 0.7874 0.4064)
			(end -0.7874 0.4064)
			(stroke
				(width 0.1524)
				(type default)
			)
			(layer "F.SilkS")
		)
		(fp_line
			(start 0.7874 -0.4064)
			(end 0.7874 0.4064)
			(stroke
				(width 0.1524)
				(type default)
			)
			(layer "F.SilkS")
		)
		(fp_line
			(start -0.7874 0.4064)
			(end -0.7874 -0.4064)
			(stroke
				(width 0.1524)
				(type default)
			)
			(layer "F.SilkS")
		)
		(fp_line
			(start -0.7874 -0.4064)
			(end 0.7874 -0.4064)
			(stroke
				(width 0.1524)
				(type default)
			)
			(layer "F.SilkS")
		)
		(fp_line
			(start 0.67945 0.3048)
			(end 0.120396 0.3048)
			(stroke
				(width 0.1)
				(type default)
			)
			(layer "F.Fab")
		)
		(fp_line
			(start 0.67945 -0.3048)
			(end 0.67945 0.3048)
			(stroke
				(width 0.1)
				(type default)
			)
			(layer "F.Fab")
		)
		(fp_line
			(start 0.12065 -0.2794)
			(end 0.12065 -0.3048)
			(stroke
				(width 0.1)
				(type default)
			)
			(layer "F.Fab")
		)
		(fp_line
			(start 0.12065 -0.3048)
			(end 0.67945 -0.3048)
			(stroke
				(width 0.1)
				(type default)
			)
			(layer "F.Fab")
		)
		(fp_line
			(start 0.120396 0.3048)
			(end 0.120396 0.2794)
			(stroke
				(width 0.1)
				(type default)
			)
			(layer "F.Fab")
		)
		(fp_line
			(start 0.120396 0.2794)
			(end -0.12065 0.2794)
			(stroke
				(width 0.1)
				(type default)
			)
			(layer "F.Fab")
		)
		(fp_line
			(start -0.12065 0.3048)
			(end -0.67945 0.3048)
			(stroke
				(width 0.1)
				(type default)
			)
			(layer "F.Fab")
		)
		(fp_line
			(start -0.12065 0.2794)
			(end -0.12065 0.3048)
			(stroke
				(width 0.1)
				(type default)
			)
			(layer "F.Fab")
		)
		(fp_line
			(start -0.12065 -0.2794)
			(end 0.12065 -0.2794)
			(stroke
				(width 0.1)
				(type default)
			)
			(layer "F.Fab")
		)
		(fp_line
			(start -0.12065 -0.305054)
			(end -0.12065 -0.2794)
			(stroke
				(width 0.1)
				(type default)
			)
			(layer "F.Fab")
		)
		(fp_line
			(start -0.67945 0.3048)
			(end -0.67945 -0.305054)
			(stroke
				(width 0.1)
				(type default)
			)
			(layer "F.Fab")
		)
		(fp_line
			(start -0.67945 -0.305054)
			(end -0.12065 -0.305054)
			(stroke
				(width 0.1)
				(type default)
			)
			(layer "F.Fab")
		)
		(pad "1" smd circle
			(at -0.40005 0 180)
			(size 0 0)
			(layers "F.Cu" "F.Mask" "F.Paste")
			(net "P0V9_RETIMER_CPU1_VCC")
		)
		(pad "2" smd circle
			(at 0.40005 0 180)
			(size 0 0)
			(layers "F.Cu" "F.Mask" "F.Paste")
			(net "P3V3_AUX")
		)
	)
)
